(kicad_pcb
	(version 20260206)
	(generator "pcbnew")
	(generator_version "10.0")
	(general
		(thickness 1.6)
		(legacy_teardrops no)
	)
	(paper "A4")
	(title_block
		(title "fcb — 12433-1M.1206WZS1330.brd")
		(comment 1 "Open Vault / Knox (Wiwynn) / footprints 347-351 of 495")
	)
	(layers
		(0 "F.Cu" signal "TOP")
		(4 "In1.Cu" signal "L2GND")
		(6 "In2.Cu" signal "L3VCC")
		(2 "B.Cu" signal "BOTTOM")
		(9 "F.Adhes" user "F.Adhesive")
		(11 "B.Adhes" user "B.Adhesive")
		(13 "F.Paste" user "Package Geometry/Pastemask Top")
		(15 "B.Paste" user "Package Geometry/Pastemask Bottom")
		(5 "F.SilkS" user "Ref Des/Silkscreen Top")
		(7 "B.SilkS" user "Ref Des/Silkscreen Bottom")
		(1 "F.Mask" user "Board Geometry/Soldermask Top")
		(3 "B.Mask" user "Board Geometry/Soldermask Bottom")
		(17 "Dwgs.User" user "User.Drawings")
		(19 "Cmts.User" user "User.Comments")
		(21 "Eco1.User" user "User.Eco1")
		(23 "Eco2.User" user "User.Eco2")
		(25 "Edge.Cuts" user "Board Geometry/Outline")
		(27 "Margin" user)
		(31 "F.CrtYd" user "Package Geometry/Place Bound Top")
		(29 "B.CrtYd" user "Package Geometry/Place Bound Bottom")
		(35 "F.Fab" user "Ref Des/Assembly Top")
		(33 "B.Fab" user "Ref Des/Assembly Bottom")
	)
	(footprint ""
		(layer "F.Cu")
		(at 7.141972 -277.643082 90)
		(property "Reference" "Q6"
			(at 0 0 90)
			(layer "F.SilkS")
			(hide yes)
			(effects
				(font
					(size 1.27 1.27)
				)
			)
		)
		(property "Value" "PMBS3904-1-GP"
			(at 0 -9.0932 90)
			(unlocked yes)
			(layer "F.Fab")
			(hide yes)
			(effects
				(font
					(size 1.016 1.016)
					(thickness 0.1524)
				)
			)
		)
		(property "Device Type" "SOT-23-10H44"
			(at 0 -10.6172 90)
			(unlocked yes)
			(layer "F.Fab")
			(hide yes)
			(effects
				(font
					(size 1.016 1.016)
					(thickness 0.1524)
				)
			)
		)
		(duplicate_pad_numbers_are_jumpers no)
		(fp_line
			(start 1.651 -1.778)
			(end -1.651 -1.778)
			(stroke
				(width 0.1524)
				(type default)
			)
			(layer "F.SilkS")
		)
		(fp_line
			(start -1.651 -1.778)
			(end -1.651 1.778)
			(stroke
				(width 0.1524)
				(type default)
			)
			(layer "F.SilkS")
		)
		(fp_line
			(start 1.651 1.778)
			(end 1.651 -1.778)
			(stroke
				(width 0.1524)
				(type default)
			)
			(layer "F.SilkS")
		)
		(fp_line
			(start -1.651 1.778)
			(end 1.651 1.778)
			(stroke
				(width 0.1524)
				(type default)
			)
			(layer "F.SilkS")
		)
		(fp_line
			(start -0.9906 1.86309)
			(end -0.701294 2.15265)
			(stroke
				(width 0.0127)
				(type default)
			)
			(layer "F.SilkS")
		)
		(fp_line
			(start -0.994156 1.8669)
			(end -0.987044 1.8669)
			(stroke
				(width 0.0127)
				(type default)
			)
			(layer "F.SilkS")
		)
		(fp_line
			(start -1.003808 1.876552)
			(end -0.977646 1.876552)
			(stroke
				(width 0.0127)
				(type default)
			)
			(layer "F.SilkS")
		)
		(fp_line
			(start -0.635 1.8796)
			(end -1.7526 1.8796)
			(stroke
				(width 0.3302)
				(type default)
			)
			(layer "F.SilkS")
		)
		(fp_line
			(start -1.7526 1.8796)
			(end -1.7526 0.9906)
			(stroke
				(width 0.3302)
				(type default)
			)
			(layer "F.SilkS")
		)
		(fp_line
			(start -1.013206 1.88595)
			(end -0.967994 1.88595)
			(stroke
				(width 0.0127)
				(type default)
			)
			(layer "F.SilkS")
		)
		(fp_line
			(start -1.022858 1.895602)
			(end -0.958596 1.895602)
			(stroke
				(width 0.0127)
				(type default)
			)
			(layer "F.SilkS")
		)
		(fp_line
			(start -1.032256 1.905)
			(end -0.948944 1.905)
			(stroke
				(width 0.0127)
				(type default)
			)
			(layer "F.SilkS")
		)
		(fp_line
			(start -1.041908 1.914652)
			(end -0.939546 1.914652)
			(stroke
				(width 0.0127)
				(type default)
			)
			(layer "F.SilkS")
		)
		(fp_line
			(start -1.051306 1.92405)
			(end -0.929894 1.92405)
			(stroke
				(width 0.0127)
				(type default)
			)
			(layer "F.SilkS")
		)
		(fp_line
			(start -1.060958 1.933702)
			(end -0.920496 1.933702)
			(stroke
				(width 0.0127)
				(type default)
			)
			(layer "F.SilkS")
		)
		(fp_line
			(start -1.070356 1.9431)
			(end -0.910844 1.9431)
			(stroke
				(width 0.0127)
				(type default)
			)
			(layer "F.SilkS")
		)
		(fp_line
			(start -1.080008 1.952752)
			(end -0.901446 1.952752)
			(stroke
				(width 0.0127)
				(type default)
			)
			(layer "F.SilkS")
		)
		(fp_line
			(start -1.089406 1.96215)
			(end -0.891794 1.96215)
			(stroke
				(width 0.0127)
				(type default)
			)
			(layer "F.SilkS")
		)
		(fp_line
			(start -1.099058 1.971802)
			(end -0.882396 1.971802)
			(stroke
				(width 0.0127)
				(type default)
			)
			(layer "F.SilkS")
		)
		(fp_line
			(start -1.108456 1.9812)
			(end -0.872744 1.9812)
			(stroke
				(width 0.0127)
				(type default)
			)
			(layer "F.SilkS")
		)
		(fp_line
			(start -1.118108 1.990852)
			(end -0.863346 1.990852)
			(stroke
				(width 0.0127)
				(type default)
			)
			(layer "F.SilkS")
		)
		(fp_line
			(start -1.127506 2.00025)
			(end -0.853694 2.00025)
			(stroke
				(width 0.0127)
				(type default)
			)
			(layer "F.SilkS")
		)
		(fp_line
			(start -1.137158 2.009902)
			(end -0.844296 2.009902)
			(stroke
				(width 0.0127)
				(type default)
			)
			(layer "F.SilkS")
		)
		(fp_line
			(start -1.146556 2.0193)
			(end -0.834644 2.0193)
			(stroke
				(width 0.0127)
				(type default)
			)
			(layer "F.SilkS")
		)
		(fp_line
			(start -1.156208 2.028952)
			(end -0.825246 2.028952)
			(stroke
				(width 0.0127)
				(type default)
			)
			(layer "F.SilkS")
		)
		(fp_line
			(start -1.165606 2.03835)
			(end -0.815594 2.03835)
			(stroke
				(width 0.0127)
				(type default)
			)
			(layer "F.SilkS")
		)
		(fp_line
			(start -1.175258 2.048002)
			(end -0.806196 2.048002)
			(stroke
				(width 0.0127)
				(type default)
			)
			(layer "F.SilkS")
		)
		(fp_line
			(start -1.184656 2.0574)
			(end -0.796544 2.0574)
			(stroke
				(width 0.0127)
				(type default)
			)
			(layer "F.SilkS")
		)
		(fp_line
			(start -1.194308 2.067052)
			(end -0.787146 2.067052)
			(stroke
				(width 0.0127)
				(type default)
			)
			(layer "F.SilkS")
		)
		(fp_line
			(start -1.203706 2.07645)
			(end -0.777494 2.07645)
			(stroke
				(width 0.0127)
				(type default)
			)
			(layer "F.SilkS")
		)
		(fp_line
			(start -1.213358 2.086102)
			(end -0.768096 2.086102)
			(stroke
				(width 0.0127)
				(type default)
			)
			(layer "F.SilkS")
		)
		(fp_line
			(start -1.222756 2.0955)
			(end -0.758444 2.0955)
			(stroke
				(width 0.0127)
				(type default)
			)
			(layer "F.SilkS")
		)
		(fp_line
			(start -1.232408 2.105152)
			(end -0.749046 2.105152)
			(stroke
				(width 0.0127)
				(type default)
			)
			(layer "F.SilkS")
		)
		(fp_line
			(start -1.241806 2.11455)
			(end -0.739394 2.11455)
			(stroke
				(width 0.0127)
				(type default)
			)
			(layer "F.SilkS")
		)
		(fp_line
			(start -1.251458 2.124202)
			(end -0.729996 2.124202)
			(stroke
				(width 0.0127)
				(type default)
			)
			(layer "F.SilkS")
		)
		(fp_line
			(start -1.260856 2.1336)
			(end -0.720344 2.1336)
			(stroke
				(width 0.0127)
				(type default)
			)
			(layer "F.SilkS")
		)
		(fp_line
			(start -0.719074 2.145538)
			(end -1.265936 2.14122)
			(stroke
				(width 0.0127)
				(type default)
			)
			(layer "F.SilkS")
		)
		(fp_line
			(start -1.279398 2.152142)
			(end -0.9906 1.86309)
			(stroke
				(width 0.0127)
				(type default)
			)
			(layer "F.SilkS")
		)
		(fp_line
			(start -0.71628 2.15265)
			(end -1.26492 2.15265)
			(stroke
				(width 0.0127)
				(type default)
			)
			(layer "F.SilkS")
		)
		(fp_line
			(start -1.279144 2.15265)
			(end -0.701294 2.15265)
			(stroke
				(width 0.0127)
				(type default)
			)
			(layer "F.SilkS")
		)
		(fp_poly
			(pts
				(xy -1.285748 2.159) (xy -1.285748 1.8796) (xy -1.778 1.8796) (xy -1.778 -1.8796) (xy 1.778 -1.8796)
				(xy 1.778 1.8796) (xy -0.694944 1.8796) (xy -0.694944 2.159)
			)
			(stroke
				(width 0)
				(type default)
			)
			(fill no)
			(layer "F.CrtYd")
		)
		(fp_poly
			(pts
				(xy -1.285748 2.159) (xy -1.285748 1.8796) (xy -1.778 1.8796) (xy -1.778 -1.8796) (xy 1.778 -1.8796)
				(xy 1.778 1.8796) (xy -0.694944 1.8796) (xy -0.694944 2.159)
			)
			(stroke
				(width 0)
				(type default)
			)
			(fill no)
			(layer "F.Fab")
		)
		(pad "1" smd rect
			(at -0.98425 0.9525 90)
			(size 0.762 1.143)
			(layers "F.Cu" "F.Mask" "F.Paste")
			(net "LED_DR_LED2_B")
		)
		(pad "2" smd rect
			(at 0.98425 0.9525 90)
			(size 0.762 1.143)
			(layers "F.Cu" "F.Mask" "F.Paste")
			(net "GND")
		)
		(pad "3" smd rect
			(at 0 -0.9525 90)
			(size 0.762 1.143)
			(layers "F.Cu" "F.Mask" "F.Paste")
			(net "LED_DR_LED2_BLUE")
		)
	)
	(footprint ""
		(layer "F.Cu")
		(at 33.069784 -353.6442 -90)
		(property "Reference" "C259"
			(at 0 0 270)
			(layer "F.SilkS")
			(hide yes)
			(effects
				(font
					(size 1.27 1.27)
				)
			)
		)
		(property "Value" "SC10U25V6KX-1GP"
			(at -0.0762 -5.1308 270)
			(unlocked yes)
			(layer "F.Fab")
			(hide yes)
			(effects
				(font
					(size 1.016 1.016)
					(thickness 0.1524)
				)
			)
		)
		(property "Device Type" "C1206H71"
			(at -0.127 -6.6548 270)
			(unlocked yes)
			(layer "F.Fab")
			(hide yes)
			(effects
				(font
					(size 1.016 1.016)
					(thickness 0.1524)
				)
			)
		)
		(duplicate_pad_numbers_are_jumpers no)
		(fp_line
			(start -1.016 2.2352)
			(end -1.016 0.8382)
			(stroke
				(width 0.1524)
				(type default)
			)
			(layer "F.SilkS")
		)
		(fp_line
			(start 1.016 2.2352)
			(end -1.016 2.2352)
			(stroke
				(width 0.1524)
				(type default)
			)
			(layer "F.SilkS")
		)
		(fp_line
			(start 1.016 0.8382)
			(end 1.016 2.2352)
			(stroke
				(width 0.1524)
				(type default)
			)
			(layer "F.SilkS")
		)
		(fp_line
			(start -1.016 -0.8382)
			(end -1.016 -2.2352)
			(stroke
				(width 0.1524)
				(type default)
			)
			(layer "F.SilkS")
		)
		(fp_line
			(start -1.016 -2.2352)
			(end 1.016 -2.2352)
			(stroke
				(width 0.1524)
				(type default)
			)
			(layer "F.SilkS")
		)
		(fp_line
			(start 1.016 -2.2352)
			(end 1.016 -0.8382)
			(stroke
				(width 0.1524)
				(type default)
			)
			(layer "F.SilkS")
		)
		(fp_rect
			(start -1.0922 2.3114)
			(end 1.0922 -2.3114)
			(stroke
				(width 0)
				(type default)
			)
			(fill no)
			(layer "F.CrtYd")
		)
		(fp_poly
			(pts
				(xy 1.0922 -2.3114) (xy 1.0922 2.3114) (xy -1.0922 2.3114) (xy -1.0922 -2.3114)
			)
			(stroke
				(width 0)
				(type default)
			)
			(fill no)
			(layer "F.Fab")
		)
		(pad "1" smd rect
			(at 0 -1.397 270)
			(size 1.651 1.27)
			(layers "F.Cu" "F.Mask" "F.Paste")
			(net "OTP_RETRY_G")
		)
		(pad "2" smd rect
			(at 0 1.397 270)
			(size 1.651 1.27)
			(layers "F.Cu" "F.Mask" "F.Paste")
			(net "GND")
		)
	)
	(footprint ""
		(layer "F.Cu")
		(at 29.852366 -242.327176)
		(property "Reference" "R43"
			(at 0 0 0)
			(layer "F.SilkS")
			(hide yes)
			(effects
				(font
					(size 1.27 1.27)
				)
			)
		)
		(property "Value" "4K7R2J-2-GP"
			(at 0.064008 -3.993896 0)
			(unlocked yes)
			(layer "F.Fab")
			(hide yes)
			(effects
				(font
					(size 1.016 1.016)
					(thickness 0.1524)
				)
			)
		)
		(property "Device Type" "R402H16"
			(at 0.064008 -5.517896 0)
			(unlocked yes)
			(layer "F.Fab")
			(hide yes)
			(effects
				(font
					(size 1.016 1.016)
					(thickness 0.1524)
				)
			)
		)
		(duplicate_pad_numbers_are_jumpers no)
		(fp_line
			(start -0.508 -0.9398)
			(end -0.508 0.9398)
			(stroke
				(width 0.1524)
				(type default)
			)
			(layer "F.SilkS")
		)
		(fp_line
			(start 0.508 -0.9398)
			(end -0.508 -0.9398)
			(stroke
				(width 0.1524)
				(type default)
			)
			(layer "F.SilkS")
		)
		(fp_rect
			(start -0.508 0.9398)
			(end 0.508 -0.9398)
			(stroke
				(width 0)
				(type default)
			)
			(fill no)
			(layer "F.CrtYd")
		)
		(fp_rect
			(start -0.508 0.9398)
			(end 0.508 -0.9398)
			(stroke
				(width 0)
				(type default)
			)
			(fill no)
			(layer "F.Fab")
		)
		(pad "1" smd custom
			(at 0 -0.4445)
			(size 0.1397 0.1397)
			(layers "F.Cu" "F.Mask" "F.Paste")
			(net "FCB_EEPROM_A1")
			(options
				(clearance outline)
				(anchor circle)
			)
			(primitives
				(gr_poly
					(pts
						(arc
							(start -0.1778 -0.2794)
							(mid -0.249642 -0.249642)
							(end -0.2794 -0.1778)
						)
						(arc
							(start -0.2794 0.1778)
							(mid -0.249642 0.249642)
							(end -0.1778 0.2794)
						)
						(arc
							(start 0.1778 0.2794)
							(mid 0.249642 0.249642)
							(end 0.2794 0.1778)
						)
						(arc
							(start 0.2794 -0.1778)
							(mid 0.249642 -0.249642)
							(end 0.1778 -0.2794)
						)
					)
					(width 0)
					(fill yes)
				)
			)
		)
		(pad "2" smd custom
			(at 0 0.4445)
			(size 0.1397 0.1397)
			(layers "F.Cu" "F.Mask" "F.Paste")
			(net "GND")
			(options
				(clearance outline)
				(anchor circle)
			)
			(primitives
				(gr_poly
					(pts
						(arc
							(start -0.1778 -0.2794)
							(mid -0.249642 -0.249642)
							(end -0.2794 -0.1778)
						)
						(arc
							(start -0.2794 0.1778)
							(mid -0.249642 0.249642)
							(end -0.1778 0.2794)
						)
						(arc
							(start 0.1778 0.2794)
							(mid 0.249642 0.249642)
							(end 0.2794 0.1778)
						)
						(arc
							(start 0.2794 -0.1778)
							(mid 0.249642 -0.249642)
							(end 0.1778 -0.2794)
						)
					)
					(width 0)
					(fill yes)
				)
			)
		)
	)
	(footprint ""
		(layer "F.Cu")
		(at 9.906 -147.2184 180)
		(property "Reference" "R66"
			(at 0 0 180)
			(layer "F.SilkS")
			(hide yes)
			(effects
				(font
					(size 1.27 1.27)
				)
			)
		)
		(property "Value" "4K7R2F-GP"
			(at 0.064008 -3.993896 180)
			(unlocked yes)
			(layer "F.Fab")
			(hide yes)
			(effects
				(font
					(size 1.016 1.016)
					(thickness 0.1524)
				)
			)
		)
		(property "Device Type" "R402H16"
			(at 0.064008 -5.517896 180)
			(unlocked yes)
			(layer "F.Fab")
			(hide yes)
			(effects
				(font
					(size 1.016 1.016)
					(thickness 0.1524)
				)
			)
		)
		(duplicate_pad_numbers_are_jumpers no)
		(fp_line
			(start 0.508 -0.9398)
			(end -0.508 -0.9398)
			(stroke
				(width 0.1524)
				(type default)
			)
			(layer "F.SilkS")
		)
		(fp_line
			(start -0.508 -0.9398)
			(end -0.508 0.9398)
			(stroke
				(width 0.1524)
				(type default)
			)
			(layer "F.SilkS")
		)
		(fp_rect
			(start -0.508 0.9398)
			(end 0.508 -0.9398)
			(stroke
				(width 0)
				(type default)
			)
			(fill no)
			(layer "F.CrtYd")
		)
		(fp_rect
			(start -0.508 0.9398)
			(end 0.508 -0.9398)
			(stroke
				(width 0)
				(type default)
			)
			(fill no)
			(layer "F.Fab")
		)
		(pad "1" smd custom
			(at 0 -0.4445 180)
			(size 0.1397 0.1397)
			(layers "F.Cu" "F.Mask" "F.Paste")
			(net "P12V")
			(options
				(clearance outline)
				(anchor circle)
			)
			(primitives
				(gr_poly
					(pts
						(arc
							(start -0.1778 -0.2794)
							(mid -0.249642 -0.249642)
							(end -0.2794 -0.1778)
						)
						(arc
							(start -0.2794 0.1778)
							(mid -0.249642 0.249642)
							(end -0.1778 0.2794)
						)
						(arc
							(start 0.1778 0.2794)
							(mid 0.249642 0.249642)
							(end 0.2794 0.1778)
						)
						(arc
							(start 0.2794 -0.1778)
							(mid 0.249642 -0.249642)
							(end 0.1778 -0.2794)
						)
					)
					(width 0)
					(fill yes)
				)
			)
		)
		(pad "2" smd custom
			(at 0 0.4445 180)
			(size 0.1397 0.1397)
			(layers "F.Cu" "F.Mask" "F.Paste")
			(net "FAN_TACH10")
			(options
				(clearance outline)
				(anchor circle)
			)
			(primitives
				(gr_poly
					(pts
						(arc
							(start -0.1778 -0.2794)
							(mid -0.249642 -0.249642)
							(end -0.2794 -0.1778)
						)
						(arc
							(start -0.2794 0.1778)
							(mid -0.249642 0.249642)
							(end -0.1778 0.2794)
						)
						(arc
							(start 0.1778 0.2794)
							(mid 0.249642 0.249642)
							(end 0.2794 0.1778)
						)
						(arc
							(start 0.2794 -0.1778)
							(mid 0.249642 -0.249642)
							(end 0.1778 -0.2794)
						)
					)
					(width 0)
					(fill yes)
				)
			)
		)
	)
	(footprint ""
		(layer "F.Cu")
		(at 38.5572 -109.4232 -90)
		(property "Reference" "PR103"
			(at 0 0 270)
			(layer "F.SilkS")
			(hide yes)
			(effects
				(font
					(size 1.27 1.27)
				)
			)
		)
		(property "Value" "10R2F-L-GP"
			(at 0.064008 -3.993896 270)
			(unlocked yes)
			(layer "F.Fab")
			(hide yes)
			(effects
				(font
					(size 1.016 1.016)
					(thickness 0.1524)
				)
			)
		)
		(property "Device Type" "R402H14"
			(at 0.064008 -5.517896 270)
			(unlocked yes)
			(layer "F.Fab")
			(hide yes)
			(effects
				(font
					(size 1.016 1.016)
					(thickness 0.1524)
				)
			)
		)
		(duplicate_pad_numbers_are_jumpers no)
		(fp_line
			(start -0.508 -0.9398)
			(end -0.508 0.9398)
			(stroke
				(width 0.1524)
				(type default)
			)
			(layer "F.SilkS")
		)
		(fp_line
			(start 0.508 -0.9398)
			(end -0.508 -0.9398)
			(stroke
				(width 0.1524)
				(type default)
			)
			(layer "F.SilkS")
		)
		(fp_rect
			(start -0.508 0.9398)
			(end 0.508 -0.9398)
			(stroke
				(width 0)
				(type default)
			)
			(fill no)
			(layer "F.CrtYd")
		)
		(fp_rect
			(start -0.508 0.9398)
			(end 0.508 -0.9398)
			(stroke
				(width 0)
				(type default)
			)
			(fill no)
			(layer "F.Fab")
		)
		(pad "1" smd custom
			(at 0 -0.4445 270)
			(size 0.1397 0.1397)
			(layers "F.Cu" "F.Mask" "F.Paste")
			(net "P12VL_2490_GATE_DRV")
			(options
				(clearance outline)
				(anchor circle)
			)
			(primitives
				(gr_poly
					(pts
						(arc
							(start -0.1778 -0.2794)
							(mid -0.249642 -0.249642)
							(end -0.2794 -0.1778)
						)
						(arc
							(start -0.2794 0.1778)
							(mid -0.249642 0.249642)
							(end -0.1778 0.2794)
						)
						(arc
							(start 0.1778 0.2794)
							(mid 0.249642 0.249642)
							(end 0.2794 0.1778)
						)
						(arc
							(start 0.2794 -0.1778)
							(mid 0.249642 -0.249642)
							(end 0.1778 -0.2794)
						)
					)
					(width 0)
					(fill yes)
				)
			)
		)
		(pad "2" smd custom
			(at 0 0.4445 270)
			(size 0.1397 0.1397)
			(layers "F.Cu" "F.Mask" "F.Paste")
			(net "P12VL_2490_GATE")
			(options
				(clearance outline)
				(anchor circle)
			)
			(primitives
				(gr_poly
					(pts
						(arc
							(start -0.1778 -0.2794)
							(mid -0.249642 -0.249642)
							(end -0.2794 -0.1778)
						)
						(arc
							(start -0.2794 0.1778)
							(mid -0.249642 0.249642)
							(end -0.1778 0.2794)
						)
						(arc
							(start 0.1778 0.2794)
							(mid 0.249642 0.249642)
							(end 0.2794 0.1778)
						)
						(arc
							(start 0.2794 -0.1778)
							(mid 0.249642 -0.249642)
							(end 0.1778 -0.2794)
						)
					)
					(width 0)
					(fill yes)
				)
			)
		)
	)
)
